# S9S_MB_2U (Grand Teton) — schematic netlist excerpt (pin names and nets, part order shuffled) for the footprints in the layout excerpt that follows; sources: Cadence DE-HDL packaged netlist, KiCad conversion of 03242023_DA0F0TMBIJ0_F0T_Motherboard_J_brd_V01_OCP.brd

R3263  Q_RES  0 5% CHIP  pkg 0402LF  page 238 : A = HP_LVC3_OCP_V3_1_R_EN ; B = HP_LVC3_OCP_V3_1_EN
PC2219  Q_CAP  10UF 16V 10% X6S  pkg C0805  page 192 : A = P12V_E1S_0 ; B = GND
C1802  Q_CAP  1000PF 50V 5% EMPTY  pkg 0402  page 148 : A = FM_SMB_1_ALERT_GPU_ISO_N ; B = GND

(kicad_pcb
	(version 20260206)
	(generator "pcbnew")
	(generator_version "10.0")
	(general
		(thickness 1.6)
		(legacy_teardrops no)
	)
	(paper "A4")
	(title_block
		(title "03242023_DA0F0TMBIJ0_F0T_Motherboard_J_brd_V01_OCP.brd")
		(comment 1 "Grand Teton / footprints 2635-2637 of 6105")
	)
	(layers
		(0 "F.Cu" signal "TOP")
		(4 "In1.Cu" signal "GND")
		(6 "In2.Cu" signal "IN1")
		(8 "In3.Cu" signal "GND1")
		(10 "In4.Cu" signal "IN2")
		(12 "In5.Cu" signal "GND2")
		(14 "In6.Cu" signal "IN3")
		(16 "In7.Cu" signal "GND3")
		(18 "In8.Cu" signal "VCC")
		(20 "In9.Cu" signal "VCC1")
		(22 "In10.Cu" signal "GND4")
		(24 "In11.Cu" signal "IN4")
		(26 "In12.Cu" signal "GND5")
		(28 "In13.Cu" signal "IN5")
		(30 "In14.Cu" signal "GND6")
		(32 "In15.Cu" signal "IN6")
		(34 "In16.Cu" signal "GND7")
		(2 "B.Cu" signal "BOTTOM")
		(9 "F.Adhes" user "F.Adhesive")
		(11 "B.Adhes" user "B.Adhesive")
		(13 "F.Paste" user "Package Geometry/Pastemask Top")
		(15 "B.Paste" user "Package Geometry/Pastemask Bottom")
		(5 "F.SilkS" user "Ref Des/Silkscreen Top")
		(7 "B.SilkS" user "Ref Des/Silkscreen Bottom")
		(1 "F.Mask" user "Board Geometry/Soldermask Top")
		(3 "B.Mask" user "Board Geometry/Soldermask Bottom")
		(17 "Dwgs.User" user "User.Drawings")
		(19 "Cmts.User" user "User.Comments")
		(21 "Eco1.User" user "User.Eco1")
		(23 "Eco2.User" user "User.Eco2")
		(25 "Edge.Cuts" user "Board Geometry/Outline")
		(27 "Margin" user)
		(31 "F.CrtYd" user "Package Geometry/Place Bound Top")
		(29 "B.CrtYd" user "Package Geometry/Place Bound Bottom")
		(35 "F.Fab" user "Ref Des/Assembly Top")
		(33 "B.Fab" user "Ref Des/Assembly Bottom")
	)
	(footprint ""
		(layer "F.Cu")
		(at 115.82908 -400.414998 90)
		(property "Reference" "C1802"
			(at 0 0 90)
			(layer "F.SilkS")
			(hide yes)
			(effects
				(font
					(size 1.27 1.27)
				)
			)
		)
		(property "Value" ""
			(at 0 0 90)
			(layer "F.Fab")
			(effects
				(font
					(size 1.27 1.27)
				)
			)
		)
		(duplicate_pad_numbers_are_jumpers no)
		(fp_line
			(start 0.7874 -0.4064)
			(end 0.7874 0.4064)
			(stroke
				(width 0.1524)
				(type default)
			)
			(layer "F.SilkS")
		)
		(fp_line
			(start -0.7874 -0.4064)
			(end 0.7874 -0.4064)
			(stroke
				(width 0.1524)
				(type default)
			)
			(layer "F.SilkS")
		)
		(fp_line
			(start 0.7874 0.4064)
			(end -0.7874 0.4064)
			(stroke
				(width 0.1524)
				(type default)
			)
			(layer "F.SilkS")
		)
		(fp_line
			(start -0.7874 0.4064)
			(end -0.7874 -0.4064)
			(stroke
				(width 0.1524)
				(type default)
			)
			(layer "F.SilkS")
		)
		(fp_line
			(start -0.12065 -0.305054)
			(end -0.12065 -0.2794)
			(stroke
				(width 0.1)
				(type default)
			)
			(layer "F.Fab")
		)
		(fp_line
			(start -0.67945 -0.305054)
			(end -0.12065 -0.305054)
			(stroke
				(width 0.1)
				(type default)
			)
			(layer "F.Fab")
		)
		(fp_line
			(start 0.67945 -0.3048)
			(end 0.67945 0.3048)
			(stroke
				(width 0.1)
				(type default)
			)
			(layer "F.Fab")
		)
		(fp_line
			(start 0.12065 -0.3048)
			(end 0.67945 -0.3048)
			(stroke
				(width 0.1)
				(type default)
			)
			(layer "F.Fab")
		)
		(fp_line
			(start 0.12065 -0.2794)
			(end 0.12065 -0.3048)
			(stroke
				(width 0.1)
				(type default)
			)
			(layer "F.Fab")
		)
		(fp_line
			(start -0.12065 -0.2794)
			(end 0.12065 -0.2794)
			(stroke
				(width 0.1)
				(type default)
			)
			(layer "F.Fab")
		)
		(fp_line
			(start 0.120396 0.2794)
			(end -0.12065 0.2794)
			(stroke
				(width 0.1)
				(type default)
			)
			(layer "F.Fab")
		)
		(fp_line
			(start -0.12065 0.2794)
			(end -0.12065 0.3048)
			(stroke
				(width 0.1)
				(type default)
			)
			(layer "F.Fab")
		)
		(fp_line
			(start 0.67945 0.3048)
			(end 0.120396 0.3048)
			(stroke
				(width 0.1)
				(type default)
			)
			(layer "F.Fab")
		)
		(fp_line
			(start 0.120396 0.3048)
			(end 0.120396 0.2794)
			(stroke
				(width 0.1)
				(type default)
			)
			(layer "F.Fab")
		)
		(fp_line
			(start -0.12065 0.3048)
			(end -0.67945 0.3048)
			(stroke
				(width 0.1)
				(type default)
			)
			(layer "F.Fab")
		)
		(fp_line
			(start -0.67945 0.3048)
			(end -0.67945 -0.305054)
			(stroke
				(width 0.1)
				(type default)
			)
			(layer "F.Fab")
		)
		(pad "1" smd circle
			(at -0.40005 0 90)
			(size 0 0)
			(layers "F.Cu" "F.Mask" "F.Paste")
			(net "FM_SMB_1_ALERT_GPU_ISO_N")
		)
		(pad "2" smd circle
			(at 0.40005 0 90)
			(size 0 0)
			(layers "F.Cu" "F.Mask" "F.Paste")
			(net "GND")
		)
	)
	(footprint ""
		(layer "F.Cu")
		(at 246.22506 -52.981606 90)
		(property "Reference" "PC2219"
			(at 0 0 90)
			(layer "F.SilkS")
			(hide yes)
			(effects
				(font
					(size 1.27 1.27)
				)
			)
		)
		(property "Value" ""
			(at 0 0 90)
			(layer "F.Fab")
			(effects
				(font
					(size 1.27 1.27)
				)
			)
		)
		(duplicate_pad_numbers_are_jumpers no)
		(fp_line
			(start 1.524 -0.762)
			(end 1.524 0.762)
			(stroke
				(width 0.1524)
				(type default)
			)
			(layer "F.SilkS")
		)
		(fp_line
			(start -1.524 -0.762)
			(end 1.524 -0.762)
			(stroke
				(width 0.1524)
				(type default)
			)
			(layer "F.SilkS")
		)
		(fp_line
			(start 1.524 0.762)
			(end -1.524 0.762)
			(stroke
				(width 0.1524)
				(type default)
			)
			(layer "F.SilkS")
		)
		(fp_line
			(start -1.524 0.762)
			(end -1.524 -0.762)
			(stroke
				(width 0.1524)
				(type default)
			)
			(layer "F.SilkS")
		)
		(fp_line
			(start 1.1049 -0.724916)
			(end -1.1049 -0.724916)
			(stroke
				(width 0.1)
				(type default)
			)
			(layer "F.Fab")
		)
		(fp_line
			(start -1.1049 -0.724916)
			(end -1.1049 0.724916)
			(stroke
				(width 0.1)
				(type default)
			)
			(layer "F.Fab")
		)
		(fp_line
			(start 1.1049 0.724916)
			(end 1.1049 -0.724916)
			(stroke
				(width 0.1)
				(type default)
			)
			(layer "F.Fab")
		)
		(fp_line
			(start -1.1049 0.724916)
			(end 1.1049 0.724916)
			(stroke
				(width 0.1)
				(type default)
			)
			(layer "F.Fab")
		)
		(pad "1" smd rect
			(at -0.889 0 270)
			(size 1.016 1.27)
			(layers "F.Cu" "F.Mask" "F.Paste")
			(net "P12V_E1S_0")
		)
		(pad "2" smd rect
			(at 0.889 0 270)
			(size 1.016 1.27)
			(layers "F.Cu" "F.Mask" "F.Paste")
			(net "GND")
		)
	)
	(footprint ""
		(layer "F.Cu")
		(at 450.43725 -43.155362)
		(property "Reference" "R3263"
			(at 0 0 0)
			(layer "F.SilkS")
			(hide yes)
			(effects
				(font
					(size 1.27 1.27)
				)
			)
		)
		(property "Value" ""
			(at 0 0 0)
			(layer "F.Fab")
			(effects
				(font
					(size 1.27 1.27)
				)
			)
		)
		(duplicate_pad_numbers_are_jumpers no)
		(fp_line
			(start -0.7874 -0.4064)
			(end 0.7874 -0.4064)
			(stroke
				(width 0.1524)
				(type default)
			)
			(layer "F.SilkS")
		)
		(fp_line
			(start -0.7874 0.4064)
			(end -0.7874 -0.4064)
			(stroke
				(width 0.1524)
				(type default)
			)
			(layer "F.SilkS")
		)
		(fp_line
			(start 0.7874 -0.4064)
			(end 0.7874 0.4064)
			(stroke
				(width 0.1524)
				(type default)
			)
			(layer "F.SilkS")
		)
		(fp_line
			(start 0.7874 0.4064)
			(end -0.7874 0.4064)
			(stroke
				(width 0.1524)
				(type default)
			)
			(layer "F.SilkS")
		)
		(fp_line
			(start -0.67945 -0.305054)
			(end -0.12065 -0.305054)
			(stroke
				(width 0.1)
				(type default)
			)
			(layer "F.Fab")
		)
		(fp_line
			(start -0.67945 0.3048)
			(end -0.67945 -0.305054)
			(stroke
				(width 0.1)
				(type default)
			)
			(layer "F.Fab")
		)
		(fp_line
			(start -0.12065 -0.305054)
			(end -0.12065 -0.2794)
			(stroke
				(width 0.1)
				(type default)
			)
			(layer "F.Fab")
		)
		(fp_line
			(start -0.12065 -0.2794)
			(end 0.12065 -0.2794)
			(stroke
				(width 0.1)
				(type default)
			)
			(layer "F.Fab")
		)
		(fp_line
			(start -0.12065 0.2794)
			(end -0.12065 0.3048)
			(stroke
				(width 0.1)
				(type default)
			)
			(layer "F.Fab")
		)
		(fp_line
			(start -0.12065 0.3048)
			(end -0.67945 0.3048)
			(stroke
				(width 0.1)
				(type default)
			)
			(layer "F.Fab")
		)
		(fp_line
			(start 0.120396 0.2794)
			(end -0.12065 0.2794)
			(stroke
				(width 0.1)
				(type default)
			)
			(layer "F.Fab")
		)
		(fp_line
			(start 0.120396 0.3048)
			(end 0.120396 0.2794)
			(stroke
				(width 0.1)
				(type default)
			)
			(layer "F.Fab")
		)
		(fp_line
			(start 0.12065 -0.3048)
			(end 0.67945 -0.3048)
			(stroke
				(width 0.1)
				(type default)
			)
			(layer "F.Fab")
		)
		(fp_line
			(start 0.12065 -0.2794)
			(end 0.12065 -0.3048)
			(stroke
				(width 0.1)
				(type default)
			)
			(layer "F.Fab")
		)
		(fp_line
			(start 0.67945 -0.3048)
			(end 0.67945 0.3048)
			(stroke
				(width 0.1)
				(type default)
			)
			(layer "F.Fab")
		)
		(fp_line
			(start 0.67945 0.3048)
			(end 0.120396 0.3048)
			(stroke
				(width 0.1)
				(type default)
			)
			(layer "F.Fab")
		)
		(pad "1" smd circle
			(at -0.40005 0)
			(size 0 0)
			(layers "F.Cu" "F.Mask" "F.Paste")
			(net "HP_LVC3_OCP_V3_1_R_EN")
		)
		(pad "2" smd circle
			(at 0.40005 0)
			(size 0 0)
			(layers "F.Cu" "F.Mask" "F.Paste")
			(net "HP_LVC3_OCP_V3_1_EN")
		)
	)
)
